(kicad_pcb
	(version 20260206)
	(generator "pcbnew")
	(generator_version "10.0")
	(general
		(thickness 1.6)
		(legacy_teardrops no)
	)
	(paper "A4")
	(title_block
		(title "Wiwynn_Tioga_Pass_MB.brd")
		(comment 1 "Tioga Pass / footprint 2254 of 4770 (U5D1), pads 3598-3647 of 3647")
	)
	(layers
		(0 "F.Cu" signal "TOP")
		(4 "In1.Cu" signal "L2GND")
		(6 "In2.Cu" signal "L3")
		(8 "In3.Cu" signal "L4GND")
		(10 "In4.Cu" signal "L5")
		(12 "In5.Cu" signal "L6GND")
		(14 "In6.Cu" signal "L7VCC")
		(16 "In7.Cu" signal "L8VCC")
		(18 "In8.Cu" signal "L9GND")
		(20 "In9.Cu" signal "L10")
		(22 "In10.Cu" signal "L11GND")
		(24 "In11.Cu" signal "L12")
		(26 "In12.Cu" signal "L13GND")
		(2 "B.Cu" signal "BOTTOM")
		(9 "F.Adhes" user "F.Adhesive")
		(11 "B.Adhes" user "B.Adhesive")
		(13 "F.Paste" user "Package Geometry/Pastemask Top")
		(15 "B.Paste" user "Package Geometry/Pastemask Bottom")
		(5 "F.SilkS" user "Ref Des/Silkscreen Top")
		(7 "B.SilkS" user "Ref Des/Silkscreen Bottom")
		(1 "F.Mask" user "Board Geometry/Soldermask Top")
		(3 "B.Mask" user "Board Geometry/Soldermask Bottom")
		(17 "Dwgs.User" user "User.Drawings")
		(19 "Cmts.User" user "User.Comments")
		(21 "Eco1.User" user "User.Eco1")
		(23 "Eco2.User" user "User.Eco2")
		(25 "Edge.Cuts" user "Board Geometry/Outline")
		(27 "Margin" user)
		(31 "F.CrtYd" user "Package Geometry/Place Bound Top")
		(29 "B.CrtYd" user "Package Geometry/Place Bound Bottom")
		(35 "F.Fab" user "Ref Des/Assembly Top")
		(33 "B.Fab" user "Ref Des/Assembly Bottom")
	)
	(footprint ""
		(layer "F.Cu")
		(at 270.000222 -76.550012 180)
		(property "Reference" "U5D1"
			(at 19.124422 31.601918 0)
			(unlocked yes)
			(layer "F.SilkS")
			(effects
				(font
					(size 0.7874 0.5842)
					(thickness 0.1524)
				)
			)
		)
		(property "Value" ""
			(at 0 0 180)
			(layer "F.Fab")
			(effects
				(font
					(size 1.27 1.27)
				)
			)
		)
		(duplicate_pad_numbers_are_jumpers no)
		(pad "W74" smd circle
			(at 26.948384 -17.988026)
			(size 0.4318 0.4318)
			(layers "F.Cu" "F.Mask" "F.Paste")
			(net "GND")
		)
		(pad "W76" smd circle
			(at 28.665424 -17.988026)
			(size 0.4318 0.4318)
			(layers "F.Cu" "F.Mask" "F.Paste")
			(net "M_C_DQ<11>")
		)
		(pad "W78" smd circle
			(at 30.382464 -17.988026)
			(size 0.4318 0.4318)
			(layers "F.Cu" "F.Mask" "F.Paste")
			(net "GND")
		)
		(pad "W80" smd circle
			(at 32.099504 -17.988026)
			(size 0.4318 0.4318)
			(layers "F.Cu" "F.Mask" "F.Paste")
			(net "M_A_DQ<20>")
		)
		(pad "W82" smd circle
			(at 33.816544 -17.988026)
			(size 0.4318 0.4318)
			(layers "F.Cu" "F.Mask" "F.Paste")
			(net "GND")
		)
		(pad "W84" smd circle
			(at 35.533584 -17.988026)
			(size 0.4318 0.4318)
			(layers "F.Cu" "F.Mask" "F.Paste")
			(net "M_A_DQ<9>")
		)
		(pad "W86" smd custom
			(at 37.250624 -17.988026 270)
			(size 0.10795 0.10795)
			(layers "F.Cu" "F.Mask" "F.Paste")
			(net "M_A_DQ<8>")
			(options
				(clearance outline)
				(anchor circle)
			)
			(primitives
				(gr_poly
					(pts
						(arc
							(start 0.2159 -0.0381)
							(mid 0 -0.254)
							(end -0.2159 -0.0381)
						)
						(arc
							(start -0.2159 0.0381)
							(mid 0 0.254)
							(end 0.2159 0.0381)
						)
					)
					(width 0)
					(fill yes)
				)
			)
		)
		(pad "Y1" smd custom
			(at -37.250624 -15.692628 90)
			(size 0.10795 0.10795)
			(layers "F.Cu" "F.Mask" "F.Paste")
			(net "UPI_CPU0_CPU1_P0P0_DN<16>")
			(options
				(clearance outline)
				(anchor circle)
			)
			(primitives
				(gr_poly
					(pts
						(arc
							(start 0.2159 -0.0381)
							(mid 0 -0.254)
							(end -0.2159 -0.0381)
						)
						(arc
							(start -0.2159 0.0381)
							(mid 0 0.254)
							(end 0.2159 0.0381)
						)
					)
					(width 0)
					(fill yes)
				)
			)
		)
		(pad "Y3" smd circle
			(at -35.533584 -15.692628)
			(size 0.4318 0.4318)
			(layers "F.Cu" "F.Mask" "F.Paste")
			(net "UPI_CPU0_CPU1_P0P0_DP<17>")
		)
		(pad "Y5" smd circle
			(at -33.816544 -15.692628)
			(size 0.4318 0.4318)
			(layers "F.Cu" "F.Mask" "F.Paste")
			(net "GND")
		)
		(pad "Y7" smd circle
			(at -32.099504 -15.692628)
			(size 0.4318 0.4318)
			(layers "F.Cu" "F.Mask" "F.Paste")
			(net "GND")
		)
		(pad "Y9" smd circle
			(at -30.382464 -15.692628)
			(size 0.4318 0.4318)
			(layers "F.Cu" "F.Mask" "F.Paste")
			(net "GND")
		)
		(pad "Y11" smd circle
			(at -28.665424 -15.692628)
			(size 0.4318 0.4318)
			(layers "F.Cu" "F.Mask" "F.Paste")
			(net "TP_XDP_CPU0_OBSDATA_A3_MBP5_N")
		)
		(pad "Y13" smd circle
			(at -26.948384 -15.692628)
			(size 0.4318 0.4318)
			(layers "F.Cu" "F.Mask" "F.Paste")
			(net "XDP_CPU_TRST_N")
		)
		(pad "Y15" smd circle
			(at -25.231598 -15.692628)
			(size 0.4318 0.4318)
			(layers "F.Cu" "F.Mask" "F.Paste")
			(net "GND")
		)
		(pad "Y17" smd circle
			(at -23.514558 -15.692628)
			(size 0.4318 0.4318)
			(layers "F.Cu" "F.Mask" "F.Paste")
			(net "GND")
		)
		(pad "Y19" smd circle
			(at -21.797518 -15.692628)
			(size 0.4318 0.4318)
			(layers "F.Cu" "F.Mask" "F.Paste")
			(net "UPI_CPU1_CPU0_P1P1_DP<2>")
		)
		(pad "Y21" smd circle
			(at -20.080478 -15.692628)
			(size 0.4318 0.4318)
			(layers "F.Cu" "F.Mask" "F.Paste")
			(net "UPI_CPU1_CPU0_P1P1_DN<1>")
		)
		(pad "Y23" smd circle
			(at -18.363438 -15.692628)
			(size 0.4318 0.4318)
			(layers "F.Cu" "F.Mask" "F.Paste")
			(net "FM_CPU0_RC_ERROR_N")
		)
		(pad "Y25" smd circle
			(at -16.646398 -15.692628)
			(size 0.4318 0.4318)
			(layers "F.Cu" "F.Mask" "F.Paste")
			(net "M_B_DQ<59>")
		)
		(pad "Y27" smd circle
			(at -14.929612 -15.692628)
			(size 0.4318 0.4318)
			(layers "F.Cu" "F.Mask" "F.Paste")
			(net "M_B_DQS_DP<7>")
		)
		(pad "Y29" smd circle
			(at -13.212572 -15.692628)
			(size 0.4318 0.4318)
			(layers "F.Cu" "F.Mask" "F.Paste")
			(net "M_B_DQ<61>")
		)
		(pad "Y31" smd circle
			(at -11.495532 -15.692628)
			(size 0.4318 0.4318)
			(layers "F.Cu" "F.Mask" "F.Paste")
			(net "M_C_DQ<43>")
		)
		(pad "Y33" smd circle
			(at -9.778492 -15.692628)
			(size 0.4318 0.4318)
			(layers "F.Cu" "F.Mask" "F.Paste")
			(net "M_C_DQS_DP<5>")
		)
		(pad "Y35" smd circle
			(at -8.061452 -15.692628)
			(size 0.4318 0.4318)
			(layers "F.Cu" "F.Mask" "F.Paste")
			(net "M_C_DQ<45>")
		)
		(pad "Y37" smd circle
			(at -6.344412 -15.692628)
			(size 0.4318 0.4318)
			(layers "F.Cu" "F.Mask" "F.Paste")
			(net "M_C_DQ<35>")
		)
		(pad "Y39" smd circle
			(at -4.627626 -15.692628)
			(size 0.4318 0.4318)
			(layers "F.Cu" "F.Mask" "F.Paste")
			(net "M_C_DQS_DP<4>")
		)
		(pad "Y41" smd circle
			(at -2.910586 -15.692628)
			(size 0.4318 0.4318)
			(layers "F.Cu" "F.Mask" "F.Paste")
			(net "M_C_DQ<37>")
		)
		(pad "Y43" smd circle
			(at -1.193546 -15.692628)
			(size 0.4318 0.4318)
			(layers "F.Cu" "F.Mask" "F.Paste")
			(net "A_CPU0_ABC_RCOMP0")
		)
		(pad "Y45" smd circle
			(at 2.052066 -17.492726)
			(size 0.508 0.508)
			(layers "F.Cu" "F.Mask" "F.Paste")
			(net "PVDDQ_ABC")
		)
		(pad "Y47" smd circle
			(at 3.769106 -17.492726)
			(size 0.4318 0.4318)
			(layers "F.Cu" "F.Mask" "F.Paste")
			(net "PVDDQ_ABC")
		)
		(pad "Y49" smd circle
			(at 5.485892 -17.492726)
			(size 0.4318 0.4318)
			(layers "F.Cu" "F.Mask" "F.Paste")
			(net "PVDDQ_ABC")
		)
		(pad "Y51" smd circle
			(at 7.202932 -17.492726)
			(size 0.4318 0.4318)
			(layers "F.Cu" "F.Mask" "F.Paste")
			(net "PVDDQ_ABC")
		)
		(pad "Y53" smd circle
			(at 8.919972 -17.492726)
			(size 0.4318 0.4318)
			(layers "F.Cu" "F.Mask" "F.Paste")
			(net "PVDDQ_ABC")
		)
		(pad "Y55" smd circle
			(at 10.637012 -17.492726)
			(size 0.4318 0.4318)
			(layers "F.Cu" "F.Mask" "F.Paste")
			(net "PVDDQ_ABC")
		)
		(pad "Y57" smd circle
			(at 12.354052 -17.492726)
			(size 0.4318 0.4318)
			(layers "F.Cu" "F.Mask" "F.Paste")
			(net "PVDDQ_ABC")
		)
		(pad "Y59" smd circle
			(at 14.071092 -17.492726)
			(size 0.4318 0.4318)
			(layers "F.Cu" "F.Mask" "F.Paste")
			(net "PVDDQ_ABC")
		)
		(pad "Y61" smd circle
			(at 15.787878 -17.492726)
			(size 0.4318 0.4318)
			(layers "F.Cu" "F.Mask" "F.Paste")
			(net "PVDDQ_ABC")
		)
		(pad "Y63" smd circle
			(at 17.504918 -17.492726)
			(size 0.4318 0.4318)
			(layers "F.Cu" "F.Mask" "F.Paste")
			(net "PVDDQ_ABC")
		)
		(pad "Y65" smd circle
			(at 19.221958 -17.492726)
			(size 0.4318 0.4318)
			(layers "F.Cu" "F.Mask" "F.Paste")
			(net "TP_CPU0_RSVD_256")
		)
		(pad "Y67" smd circle
			(at 20.938998 -17.492726)
			(size 0.4318 0.4318)
			(layers "F.Cu" "F.Mask" "F.Paste")
			(net "GND")
		)
		(pad "Y69" smd circle
			(at 22.656038 -17.492726)
			(size 0.4318 0.4318)
			(layers "F.Cu" "F.Mask" "F.Paste")
			(net "M_C_DQS_DN<2>")
		)
		(pad "Y71" smd circle
			(at 24.373078 -17.492726)
			(size 0.4318 0.4318)
			(layers "F.Cu" "F.Mask" "F.Paste")
			(net "GND")
		)
		(pad "Y73" smd circle
			(at 26.090118 -17.492726)
			(size 0.4318 0.4318)
			(layers "F.Cu" "F.Mask" "F.Paste")
			(net "GND")
		)
		(pad "Y75" smd circle
			(at 27.806904 -17.492726)
			(size 0.4318 0.4318)
			(layers "F.Cu" "F.Mask" "F.Paste")
			(net "M_C_DQ<15>")
		)
		(pad "Y77" smd circle
			(at 29.523944 -17.492726)
			(size 0.4318 0.4318)
			(layers "F.Cu" "F.Mask" "F.Paste")
			(net "M_C_DQ<10>")
		)
		(pad "Y79" smd circle
			(at 31.240984 -17.492726)
			(size 0.4318 0.4318)
			(layers "F.Cu" "F.Mask" "F.Paste")
			(net "GND")
		)
		(pad "Y81" smd circle
			(at 32.958024 -17.492726)
			(size 0.4318 0.4318)
			(layers "F.Cu" "F.Mask" "F.Paste")
			(net "GND")
		)
		(pad "Y83" smd circle
			(at 34.675064 -17.492726)
			(size 0.4318 0.4318)
			(layers "F.Cu" "F.Mask" "F.Paste")
			(net "GND")
		)
		(pad "Y85" smd circle
			(at 36.392104 -17.492726)
			(size 0.4318 0.4318)
			(layers "F.Cu" "F.Mask" "F.Paste")
			(net "GND")
		)
	)
)
